# S9S_MB_2U (Grand Teton) — schematic netlist excerpt (pin names and nets, part order shuffled) for the footprints in the layout excerpt that follows; sources: Cadence DE-HDL packaged netlist, KiCad conversion of 03242023_DA0F0TMBIJ0_F0T_Motherboard_J_brd_V01_OCP.brd

R2529  Q_RES  0 5% CHIP  pkg 0402LF  page 247 : A = FM_P12V_HSC_EN_N ; B = FM_P12V_HSC_EN_R_N
R972  Q_RES  240 1% CHIP  pkg 0402LF  page 236 : A = PVNN_TERM_CPU1 ; B = SMB_S3M_CPU1_R_SDA

(kicad_pcb
	(version 20260206)
	(generator "pcbnew")
	(generator_version "10.0")
	(general
		(thickness 1.6)
		(legacy_teardrops no)
	)
	(paper "A4")
	(title_block
		(title "03242023_DA0F0TMBIJ0_F0T_Motherboard_J_brd_V01_OCP.brd")
		(comment 1 "Grand Teton / footprints 2883-2884 of 6105")
	)
	(layers
		(0 "F.Cu" signal "TOP")
		(4 "In1.Cu" signal "GND")
		(6 "In2.Cu" signal "IN1")
		(8 "In3.Cu" signal "GND1")
		(10 "In4.Cu" signal "IN2")
		(12 "In5.Cu" signal "GND2")
		(14 "In6.Cu" signal "IN3")
		(16 "In7.Cu" signal "GND3")
		(18 "In8.Cu" signal "VCC")
		(20 "In9.Cu" signal "VCC1")
		(22 "In10.Cu" signal "GND4")
		(24 "In11.Cu" signal "IN4")
		(26 "In12.Cu" signal "GND5")
		(28 "In13.Cu" signal "IN5")
		(30 "In14.Cu" signal "GND6")
		(32 "In15.Cu" signal "IN6")
		(34 "In16.Cu" signal "GND7")
		(2 "B.Cu" signal "BOTTOM")
		(9 "F.Adhes" user "F.Adhesive")
		(11 "B.Adhes" user "B.Adhesive")
		(13 "F.Paste" user "Package Geometry/Pastemask Top")
		(15 "B.Paste" user "Package Geometry/Pastemask Bottom")
		(5 "F.SilkS" user "Ref Des/Silkscreen Top")
		(7 "B.SilkS" user "Ref Des/Silkscreen Bottom")
		(1 "F.Mask" user "Board Geometry/Soldermask Top")
		(3 "B.Mask" user "Board Geometry/Soldermask Bottom")
		(17 "Dwgs.User" user "User.Drawings")
		(19 "Cmts.User" user "User.Comments")
		(21 "Eco1.User" user "User.Eco1")
		(23 "Eco2.User" user "User.Eco2")
		(25 "Edge.Cuts" user "Board Geometry/Outline")
		(27 "Margin" user)
		(31 "F.CrtYd" user "Package Geometry/Place Bound Top")
		(29 "B.CrtYd" user "Package Geometry/Place Bound Bottom")
		(35 "F.Fab" user "Ref Des/Assembly Top")
		(33 "B.Fab" user "Ref Des/Assembly Bottom")
	)
	(footprint ""
		(layer "F.Cu")
		(at 200.03008 -131.694428 90)
		(property "Reference" "R2529"
			(at 0 0 90)
			(layer "F.SilkS")
			(hide yes)
			(effects
				(font
					(size 1.27 1.27)
				)
			)
		)
		(property "Value" ""
			(at 0 0 90)
			(layer "F.Fab")
			(effects
				(font
					(size 1.27 1.27)
				)
			)
		)
		(duplicate_pad_numbers_are_jumpers no)
		(fp_line
			(start 0.7874 -0.4064)
			(end 0.7874 0.4064)
			(stroke
				(width 0.1524)
				(type default)
			)
			(layer "F.SilkS")
		)
		(fp_line
			(start -0.7874 -0.4064)
			(end 0.7874 -0.4064)
			(stroke
				(width 0.1524)
				(type default)
			)
			(layer "F.SilkS")
		)
		(fp_line
			(start 0.7874 0.4064)
			(end -0.7874 0.4064)
			(stroke
				(width 0.1524)
				(type default)
			)
			(layer "F.SilkS")
		)
		(fp_line
			(start -0.7874 0.4064)
			(end -0.7874 -0.4064)
			(stroke
				(width 0.1524)
				(type default)
			)
			(layer "F.SilkS")
		)
		(fp_line
			(start -0.12065 -0.305054)
			(end -0.12065 -0.2794)
			(stroke
				(width 0.1)
				(type default)
			)
			(layer "F.Fab")
		)
		(fp_line
			(start -0.67945 -0.305054)
			(end -0.12065 -0.305054)
			(stroke
				(width 0.1)
				(type default)
			)
			(layer "F.Fab")
		)
		(fp_line
			(start 0.67945 -0.3048)
			(end 0.67945 0.3048)
			(stroke
				(width 0.1)
				(type default)
			)
			(layer "F.Fab")
		)
		(fp_line
			(start 0.12065 -0.3048)
			(end 0.67945 -0.3048)
			(stroke
				(width 0.1)
				(type default)
			)
			(layer "F.Fab")
		)
		(fp_line
			(start 0.12065 -0.2794)
			(end 0.12065 -0.3048)
			(stroke
				(width 0.1)
				(type default)
			)
			(layer "F.Fab")
		)
		(fp_line
			(start -0.12065 -0.2794)
			(end 0.12065 -0.2794)
			(stroke
				(width 0.1)
				(type default)
			)
			(layer "F.Fab")
		)
		(fp_line
			(start 0.120396 0.2794)
			(end -0.12065 0.2794)
			(stroke
				(width 0.1)
				(type default)
			)
			(layer "F.Fab")
		)
		(fp_line
			(start -0.12065 0.2794)
			(end -0.12065 0.3048)
			(stroke
				(width 0.1)
				(type default)
			)
			(layer "F.Fab")
		)
		(fp_line
			(start 0.67945 0.3048)
			(end 0.120396 0.3048)
			(stroke
				(width 0.1)
				(type default)
			)
			(layer "F.Fab")
		)
		(fp_line
			(start 0.120396 0.3048)
			(end 0.120396 0.2794)
			(stroke
				(width 0.1)
				(type default)
			)
			(layer "F.Fab")
		)
		(fp_line
			(start -0.12065 0.3048)
			(end -0.67945 0.3048)
			(stroke
				(width 0.1)
				(type default)
			)
			(layer "F.Fab")
		)
		(fp_line
			(start -0.67945 0.3048)
			(end -0.67945 -0.305054)
			(stroke
				(width 0.1)
				(type default)
			)
			(layer "F.Fab")
		)
		(pad "1" smd circle
			(at -0.40005 0 90)
			(size 0 0)
			(layers "F.Cu" "F.Mask" "F.Paste")
			(net "FM_P12V_HSC_EN_N")
		)
		(pad "2" smd circle
			(at 0.40005 0 90)
			(size 0 0)
			(layers "F.Cu" "F.Mask" "F.Paste")
			(net "FM_P12V_HSC_EN_R_N")
		)
	)
	(footprint ""
		(layer "F.Cu")
		(at 226.903788 -222.09887 180)
		(property "Reference" "R972"
			(at 0 0 180)
			(layer "F.SilkS")
			(hide yes)
			(effects
				(font
					(size 1.27 1.27)
				)
			)
		)
		(property "Value" ""
			(at 0 0 180)
			(layer "F.Fab")
			(effects
				(font
					(size 1.27 1.27)
				)
			)
		)
		(duplicate_pad_numbers_are_jumpers no)
		(fp_line
			(start 0.7874 0.4064)
			(end -0.7874 0.4064)
			(stroke
				(width 0.1524)
				(type default)
			)
			(layer "F.SilkS")
		)
		(fp_line
			(start 0.7874 -0.4064)
			(end 0.7874 0.4064)
			(stroke
				(width 0.1524)
				(type default)
			)
			(layer "F.SilkS")
		)
		(fp_line
			(start -0.7874 0.4064)
			(end -0.7874 -0.4064)
			(stroke
				(width 0.1524)
				(type default)
			)
			(layer "F.SilkS")
		)
		(fp_line
			(start -0.7874 -0.4064)
			(end 0.7874 -0.4064)
			(stroke
				(width 0.1524)
				(type default)
			)
			(layer "F.SilkS")
		)
		(fp_line
			(start 0.67945 0.3048)
			(end 0.120396 0.3048)
			(stroke
				(width 0.1)
				(type default)
			)
			(layer "F.Fab")
		)
		(fp_line
			(start 0.67945 -0.3048)
			(end 0.67945 0.3048)
			(stroke
				(width 0.1)
				(type default)
			)
			(layer "F.Fab")
		)
		(fp_line
			(start 0.12065 -0.2794)
			(end 0.12065 -0.3048)
			(stroke
				(width 0.1)
				(type default)
			)
			(layer "F.Fab")
		)
		(fp_line
			(start 0.12065 -0.3048)
			(end 0.67945 -0.3048)
			(stroke
				(width 0.1)
				(type default)
			)
			(layer "F.Fab")
		)
		(fp_line
			(start 0.120396 0.3048)
			(end 0.120396 0.2794)
			(stroke
				(width 0.1)
				(type default)
			)
			(layer "F.Fab")
		)
		(fp_line
			(start 0.120396 0.2794)
			(end -0.12065 0.2794)
			(stroke
				(width 0.1)
				(type default)
			)
			(layer "F.Fab")
		)
		(fp_line
			(start -0.12065 0.3048)
			(end -0.67945 0.3048)
			(stroke
				(width 0.1)
				(type default)
			)
			(layer "F.Fab")
		)
		(fp_line
			(start -0.12065 0.2794)
			(end -0.12065 0.3048)
			(stroke
				(width 0.1)
				(type default)
			)
			(layer "F.Fab")
		)
		(fp_line
			(start -0.12065 -0.2794)
			(end 0.12065 -0.2794)
			(stroke
				(width 0.1)
				(type default)
			)
			(layer "F.Fab")
		)
		(fp_line
			(start -0.12065 -0.305054)
			(end -0.12065 -0.2794)
			(stroke
				(width 0.1)
				(type default)
			)
			(layer "F.Fab")
		)
		(fp_line
			(start -0.67945 0.3048)
			(end -0.67945 -0.305054)
			(stroke
				(width 0.1)
				(type default)
			)
			(layer "F.Fab")
		)
		(fp_line
			(start -0.67945 -0.305054)
			(end -0.12065 -0.305054)
			(stroke
				(width 0.1)
				(type default)
			)
			(layer "F.Fab")
		)
		(pad "1" smd circle
			(at -0.40005 0 180)
			(size 0 0)
			(layers "F.Cu" "F.Mask" "F.Paste")
			(net "PVNN_TERM_CPU1")
		)
		(pad "2" smd circle
			(at 0.40005 0 180)
			(size 0 0)
			(layers "F.Cu" "F.Mask" "F.Paste")
			(net "SMB_S3M_CPU1_R_SDA")
		)
	)
)
